# T6G (Grand Teton) — schematic netlist excerpt (pin names and nets, part order shuffled) for the footprints in the layout excerpt that follows; sources: Cadence DE-HDL packaged netlist, KiCad conversion of 04192023_DAF0TMB3IC0_F0TG_MB_C_brd_V02_OCP.brd

R9022  Q_RES  33.2 1% CHIP  pkg 0402LF  page 136 : A = OCP_V3_1_P3V3_R3_PWRGD ; B = HP_LVC3_OCP_V3_1_PWRGD
PC6019  Q_CAP  330PF 50V 10% X7R  pkg 0402  page 269 : A = P1V8_AUX_FB ; B = P1V8_AUX

(kicad_pcb
	(version 20260206)
	(generator "pcbnew")
	(generator_version "10.0")
	(general
		(thickness 1.6)
		(legacy_teardrops no)
	)
	(paper "A4")
	(title_block
		(title "04192023_DAF0TMB3IC0_F0TG_MB_C_brd_V02_OCP.brd")
		(comment 1 "Grand Teton / footprints 4028-4029 of 8354")
	)
	(layers
		(0 "F.Cu" signal "TOP")
		(4 "In1.Cu" signal "GND")
		(6 "In2.Cu" signal "IN1")
		(8 "In3.Cu" signal "GND1")
		(10 "In4.Cu" signal "IN2")
		(12 "In5.Cu" signal "GND2")
		(14 "In6.Cu" signal "IN3")
		(16 "In7.Cu" signal "GND3")
		(18 "In8.Cu" signal "VCC")
		(20 "In9.Cu" signal "VCC1")
		(22 "In10.Cu" signal "GND4")
		(24 "In11.Cu" signal "IN4")
		(26 "In12.Cu" signal "GND5")
		(28 "In13.Cu" signal "IN5")
		(30 "In14.Cu" signal "GND6")
		(32 "In15.Cu" signal "IN6")
		(34 "In16.Cu" signal "GND7")
		(2 "B.Cu" signal "BOTTOM")
		(9 "F.Adhes" user "F.Adhesive")
		(11 "B.Adhes" user "B.Adhesive")
		(13 "F.Paste" user "Package Geometry/Pastemask Top")
		(15 "B.Paste" user "Package Geometry/Pastemask Bottom")
		(5 "F.SilkS" user "Ref Des/Silkscreen Top")
		(7 "B.SilkS" user "Ref Des/Silkscreen Bottom")
		(1 "F.Mask" user "Board Geometry/Soldermask Top")
		(3 "B.Mask" user "Board Geometry/Soldermask Bottom")
		(17 "Dwgs.User" user "User.Drawings")
		(19 "Cmts.User" user "User.Comments")
		(21 "Eco1.User" user "User.Eco1")
		(23 "Eco2.User" user "User.Eco2")
		(25 "Edge.Cuts" user "Board Geometry/Outline")
		(27 "Margin" user)
		(31 "F.CrtYd" user "Package Geometry/Place Bound Top")
		(29 "B.CrtYd" user "Package Geometry/Place Bound Bottom")
		(35 "F.Fab" user "Ref Des/Assembly Top")
		(33 "B.Fab" user "Ref Des/Assembly Bottom")
	)
	(footprint ""
		(layer "F.Cu")
		(at 215.519 -115.951 90)
		(property "Reference" "R9022"
			(at 0 0 90)
			(layer "F.SilkS")
			(hide yes)
			(effects
				(font
					(size 1.27 1.27)
				)
			)
		)
		(property "Value" ""
			(at 0 0 90)
			(layer "F.Fab")
			(effects
				(font
					(size 1.27 1.27)
				)
			)
		)
		(duplicate_pad_numbers_are_jumpers no)
		(fp_line
			(start 0.7874 -0.4064)
			(end 0.7874 0.4064)
			(stroke
				(width 0.1524)
				(type default)
			)
			(layer "F.SilkS")
		)
		(fp_line
			(start -0.7874 -0.4064)
			(end 0.7874 -0.4064)
			(stroke
				(width 0.1524)
				(type default)
			)
			(layer "F.SilkS")
		)
		(fp_line
			(start 0.7874 0.4064)
			(end -0.7874 0.4064)
			(stroke
				(width 0.1524)
				(type default)
			)
			(layer "F.SilkS")
		)
		(fp_line
			(start -0.7874 0.4064)
			(end -0.7874 -0.4064)
			(stroke
				(width 0.1524)
				(type default)
			)
			(layer "F.SilkS")
		)
		(fp_line
			(start -0.12065 -0.305054)
			(end -0.12065 -0.2794)
			(stroke
				(width 0.1)
				(type default)
			)
			(layer "F.Fab")
		)
		(fp_line
			(start -0.67945 -0.305054)
			(end -0.12065 -0.305054)
			(stroke
				(width 0.1)
				(type default)
			)
			(layer "F.Fab")
		)
		(fp_line
			(start 0.67945 -0.3048)
			(end 0.67945 0.3048)
			(stroke
				(width 0.1)
				(type default)
			)
			(layer "F.Fab")
		)
		(fp_line
			(start 0.12065 -0.3048)
			(end 0.67945 -0.3048)
			(stroke
				(width 0.1)
				(type default)
			)
			(layer "F.Fab")
		)
		(fp_line
			(start 0.12065 -0.2794)
			(end 0.12065 -0.3048)
			(stroke
				(width 0.1)
				(type default)
			)
			(layer "F.Fab")
		)
		(fp_line
			(start -0.12065 -0.2794)
			(end 0.12065 -0.2794)
			(stroke
				(width 0.1)
				(type default)
			)
			(layer "F.Fab")
		)
		(fp_line
			(start 0.120396 0.2794)
			(end -0.12065 0.2794)
			(stroke
				(width 0.1)
				(type default)
			)
			(layer "F.Fab")
		)
		(fp_line
			(start -0.12065 0.2794)
			(end -0.12065 0.3048)
			(stroke
				(width 0.1)
				(type default)
			)
			(layer "F.Fab")
		)
		(fp_line
			(start 0.67945 0.3048)
			(end 0.120396 0.3048)
			(stroke
				(width 0.1)
				(type default)
			)
			(layer "F.Fab")
		)
		(fp_line
			(start 0.120396 0.3048)
			(end 0.120396 0.2794)
			(stroke
				(width 0.1)
				(type default)
			)
			(layer "F.Fab")
		)
		(fp_line
			(start -0.12065 0.3048)
			(end -0.67945 0.3048)
			(stroke
				(width 0.1)
				(type default)
			)
			(layer "F.Fab")
		)
		(fp_line
			(start -0.67945 0.3048)
			(end -0.67945 -0.305054)
			(stroke
				(width 0.1)
				(type default)
			)
			(layer "F.Fab")
		)
		(pad "1" smd circle
			(at -0.40005 0 90)
			(size 0 0)
			(layers "F.Cu" "F.Mask" "F.Paste")
			(net "OCP_V3_1_P3V3_R3_PWRGD")
		)
		(pad "2" smd circle
			(at 0.40005 0 90)
			(size 0 0)
			(layers "F.Cu" "F.Mask" "F.Paste")
			(net "HP_LVC3_OCP_V3_1_PWRGD")
		)
	)
	(footprint ""
		(layer "F.Cu")
		(at 142.729712 -74.609452)
		(property "Reference" "PC6019"
			(at 0 0 0)
			(layer "F.SilkS")
			(hide yes)
			(effects
				(font
					(size 1.27 1.27)
				)
			)
		)
		(property "Value" ""
			(at 0 0 0)
			(layer "F.Fab")
			(effects
				(font
					(size 1.27 1.27)
				)
			)
		)
		(duplicate_pad_numbers_are_jumpers no)
		(fp_line
			(start -0.7874 -0.4064)
			(end 0.7874 -0.4064)
			(stroke
				(width 0.1524)
				(type default)
			)
			(layer "F.SilkS")
		)
		(fp_line
			(start -0.7874 0.4064)
			(end -0.7874 -0.4064)
			(stroke
				(width 0.1524)
				(type default)
			)
			(layer "F.SilkS")
		)
		(fp_line
			(start 0.7874 -0.4064)
			(end 0.7874 0.4064)
			(stroke
				(width 0.1524)
				(type default)
			)
			(layer "F.SilkS")
		)
		(fp_line
			(start 0.7874 0.4064)
			(end -0.7874 0.4064)
			(stroke
				(width 0.1524)
				(type default)
			)
			(layer "F.SilkS")
		)
		(fp_line
			(start -0.67945 -0.305054)
			(end -0.12065 -0.305054)
			(stroke
				(width 0.1)
				(type default)
			)
			(layer "F.Fab")
		)
		(fp_line
			(start -0.67945 0.3048)
			(end -0.67945 -0.305054)
			(stroke
				(width 0.1)
				(type default)
			)
			(layer "F.Fab")
		)
		(fp_line
			(start -0.12065 -0.305054)
			(end -0.12065 -0.2794)
			(stroke
				(width 0.1)
				(type default)
			)
			(layer "F.Fab")
		)
		(fp_line
			(start -0.12065 -0.2794)
			(end 0.12065 -0.2794)
			(stroke
				(width 0.1)
				(type default)
			)
			(layer "F.Fab")
		)
		(fp_line
			(start -0.12065 0.2794)
			(end -0.12065 0.3048)
			(stroke
				(width 0.1)
				(type default)
			)
			(layer "F.Fab")
		)
		(fp_line
			(start -0.12065 0.3048)
			(end -0.67945 0.3048)
			(stroke
				(width 0.1)
				(type default)
			)
			(layer "F.Fab")
		)
		(fp_line
			(start 0.120396 0.2794)
			(end -0.12065 0.2794)
			(stroke
				(width 0.1)
				(type default)
			)
			(layer "F.Fab")
		)
		(fp_line
			(start 0.120396 0.3048)
			(end 0.120396 0.2794)
			(stroke
				(width 0.1)
				(type default)
			)
			(layer "F.Fab")
		)
		(fp_line
			(start 0.12065 -0.3048)
			(end 0.67945 -0.3048)
			(stroke
				(width 0.1)
				(type default)
			)
			(layer "F.Fab")
		)
		(fp_line
			(start 0.12065 -0.2794)
			(end 0.12065 -0.3048)
			(stroke
				(width 0.1)
				(type default)
			)
			(layer "F.Fab")
		)
		(fp_line
			(start 0.67945 -0.3048)
			(end 0.67945 0.3048)
			(stroke
				(width 0.1)
				(type default)
			)
			(layer "F.Fab")
		)
		(fp_line
			(start 0.67945 0.3048)
			(end 0.120396 0.3048)
			(stroke
				(width 0.1)
				(type default)
			)
			(layer "F.Fab")
		)
		(pad "1" smd circle
			(at -0.40005 0)
			(size 0 0)
			(layers "F.Cu" "F.Mask" "F.Paste")
			(net "P1V8_AUX_FB")
		)
		(pad "2" smd circle
			(at 0.40005 0)
			(size 0 0)
			(layers "F.Cu" "F.Mask" "F.Paste")
			(net "P1V8_AUX")
		)
	)
)
